(kicad_pcb
	(version 20260206)
	(generator "pcbnew")
	(generator_version "10.0")
	(general
		(thickness 1.6)
		(legacy_teardrops no)
	)
	(paper "A4")
	(title_block
		(title "pdpb — Lightning_PDPB_BRD.brd")
		(comment 1 "Lightning (Wiwynn / Facebook NVMe JBOF) / footprints 423-428 of 1140")
	)
	(layers
		(0 "F.Cu" signal "TOP")
		(4 "In1.Cu" signal "L2GND")
		(6 "In2.Cu" signal "L3")
		(8 "In3.Cu" signal "L4VCC")
		(10 "In4.Cu" signal "L5VCC")
		(12 "In5.Cu" signal "L6")
		(14 "In6.Cu" signal "L7GND")
		(2 "B.Cu" signal "BOTTOM")
		(9 "F.Adhes" user "F.Adhesive")
		(11 "B.Adhes" user "B.Adhesive")
		(13 "F.Paste" user "Package Geometry/Pastemask Top")
		(15 "B.Paste" user "Package Geometry/Pastemask Bottom")
		(5 "F.SilkS" user "Ref Des/Silkscreen Top")
		(7 "B.SilkS" user "Ref Des/Silkscreen Bottom")
		(1 "F.Mask" user "Board Geometry/Soldermask Top")
		(3 "B.Mask" user "Board Geometry/Soldermask Bottom")
		(17 "Dwgs.User" user "User.Drawings")
		(19 "Cmts.User" user "User.Comments")
		(21 "Eco1.User" user "User.Eco1")
		(23 "Eco2.User" user "User.Eco2")
		(25 "Edge.Cuts" user "Board Geometry/Outline")
		(27 "Margin" user)
		(31 "F.CrtYd" user "Package Geometry/Place Bound Top")
		(29 "B.CrtYd" user "Package Geometry/Place Bound Bottom")
		(35 "F.Fab" user "Ref Des/Assembly Top")
		(33 "B.Fab" user "Ref Des/Assembly Bottom")
	)
	(footprint ""
		(layer "F.Cu")
		(at 8.50011 -71.499984)
		(property "Reference" "H9"
			(at 0 0 0)
			(layer "F.SilkS")
			(hide yes)
			(effects
				(font
					(size 1.27 1.27)
				)
			)
		)
		(property "Value" "GEN276X162R197X296-6-F-A-GP"
			(at -6.7183 4.1402 0)
			(unlocked yes)
			(layer "F.Fab")
			(hide yes)
			(effects
				(font
					(size 1.016 1.016)
					(thickness 0.1524)
				)
			)
		)
		(property "Device Type" "GEN276X162R197X296-6-F-A"
			(at -6.7183 2.6162 0)
			(unlocked yes)
			(layer "F.Fab")
			(hide yes)
			(effects
				(font
					(size 1.016 1.016)
					(thickness 0.1524)
				)
			)
		)
		(duplicate_pad_numbers_are_jumpers no)
		(fp_poly
			(pts
				(arc
					(start 2.723642 4.777232)
					(mid -0.000169 6.508462)
					(end -2.723896 4.776978)
				)
				(arc
					(start -2.723896 4.776978)
					(mid 0.000173 -5.499012)
					(end 2.723642 4.777232)
				)
			)
			(stroke
				(width 0)
				(type default)
			)
			(fill no)
			(layer "B.CrtYd")
		)
		(fp_poly
			(pts
				(arc
					(start 2.723642 4.777232)
					(mid -0.000169 6.508462)
					(end -2.723896 4.776978)
				)
				(arc
					(start -2.723896 4.776978)
					(mid 0.000173 -5.499012)
					(end 2.723642 4.777232)
				)
			)
			(stroke
				(width 0)
				(type default)
			)
			(fill no)
			(layer "F.CrtYd")
		)
		(fp_poly
			(pts
				(arc
					(start 2.723642 4.777232)
					(mid -0.000169 6.508462)
					(end -2.723896 4.776978)
				)
				(arc
					(start -2.723896 4.776978)
					(mid 0.000173 -5.499012)
					(end 2.723642 4.777232)
				)
			)
			(stroke
				(width 0)
				(type default)
			)
			(fill no)
			(layer "B.Fab")
		)
		(fp_poly
			(pts
				(arc
					(start 2.723642 4.777232)
					(mid -0.000169 6.508462)
					(end -2.723896 4.776978)
				)
				(arc
					(start -2.723896 4.776978)
					(mid 0.000173 -5.499012)
					(end 2.723642 4.777232)
				)
			)
			(stroke
				(width 0)
				(type default)
			)
			(fill no)
			(layer "F.Fab")
		)
		(pad "" np_thru_hole circle
			(at 0 0)
			(size 0.254 0.254)
			(drill 0.0254)
			(layers "*.Cu" "*.Mask")
			(clearance 3.135376)
			(thermal_gap 3.135376)
		)
		(pad "1" thru_hole circle
			(at 2.549906 0)
			(size 0.8636 0.8636)
			(drill 0.508)
			(layers "*.Cu" "*.Mask")
			(remove_unused_layers no)
			(net "GND")
			(clearance 0.8255)
			(thermal_gap 0.8255)
		)
		(pad "2" thru_hole circle
			(at 2.210054 -1.27)
			(size 0.8636 0.8636)
			(drill 0.508)
			(layers "*.Cu" "*.Mask")
			(remove_unused_layers no)
			(net "GND")
			(clearance 0.8255)
			(thermal_gap 0.8255)
		)
		(pad "3" thru_hole circle
			(at 1.27 -2.210054)
			(size 0.8636 0.8636)
			(drill 0.508)
			(layers "*.Cu" "*.Mask")
			(remove_unused_layers no)
			(net "GND")
			(clearance 0.8255)
			(thermal_gap 0.8255)
		)
		(pad "4" thru_hole circle
			(at -1.279906 -2.210054)
			(size 0.8636 0.8636)
			(drill 0.508)
			(layers "*.Cu" "*.Mask")
			(remove_unused_layers no)
			(net "GND")
			(clearance 0.8255)
			(thermal_gap 0.8255)
		)
		(pad "5" thru_hole circle
			(at -2.210054 -1.27)
			(size 0.8636 0.8636)
			(drill 0.508)
			(layers "*.Cu" "*.Mask")
			(remove_unused_layers no)
			(net "GND")
			(clearance 0.8255)
			(thermal_gap 0.8255)
		)
		(pad "6" thru_hole circle
			(at -2.549906 0)
			(size 0.8636 0.8636)
			(drill 0.508)
			(layers "*.Cu" "*.Mask")
			(remove_unused_layers no)
			(net "GND")
			(clearance 0.8255)
			(thermal_gap 0.8255)
		)
		(zone
			(layers "F.Cu" "B.Cu" "In1.Cu" "In2.Cu" "In3.Cu" "In4.Cu" "In5.Cu" "In6.Cu")
			(hatch none 0.5)
			(connect_pads
				(clearance 0)
			)
			(min_thickness 0.25)
			(keepout
				(tracks allowed)
				(vias not_allowed)
				(pads allowed)
				(copperpour not_allowed)
				(footprints allowed)
			)
			(placement
				(enabled no)
				(sheetname "")
			)
			(fill
				(thermal_gap 0.5)
				(thermal_bridge_width 0.5)
				(island_removal_mode 0)
			)
			(polygon
				(pts
					(arc
						(start 12.81811 -71.503032)
						(mid 4.18211 -71.503032)
						(end 12.81811 -71.503032)
					)
				)
			)
		)
		(zone
			(layers "F.Cu" "B.Cu" "In1.Cu" "In2.Cu" "In3.Cu" "In4.Cu" "In5.Cu" "In6.Cu")
			(hatch none 0.5)
			(connect_pads
				(clearance 0)
			)
			(min_thickness 0.25)
			(keepout
				(tracks not_allowed)
				(vias allowed)
				(pads allowed)
				(copperpour not_allowed)
				(footprints allowed)
			)
			(placement
				(enabled no)
				(sheetname "")
			)
			(fill
				(thermal_gap 0.5)
				(thermal_bridge_width 0.5)
				(island_removal_mode 0)
			)
			(polygon
				(pts
					(arc
						(start 10.83945 -69.89064)
						(mid 8.50019 -64.991537)
						(end 6.160516 -69.89064)
					)
					(arc
						(start 6.160516 -69.89064)
						(mid 6.406483 -70.331006)
						(end 6.491732 -70.828154)
					)
					(arc
						(start 6.491732 -71.499984)
						(mid 8.50011 -73.508362)
						(end 10.508234 -71.499984)
					)
					(arc
						(start 10.508234 -70.828154)
						(mid 10.593469 -70.331)
						(end 10.83945 -69.89064)
					)
				)
			)
		)
	)
	(footprint ""
		(layer "F.Cu")
		(at 24.003 -259.334 -90)
		(property "Reference" "R9477"
			(at 0 0 270)
			(layer "F.SilkS")
			(hide yes)
			(effects
				(font
					(size 1.27 1.27)
				)
			)
		)
		(property "Value" "330R2F-GP"
			(at 0.064008 -3.993896 270)
			(unlocked yes)
			(layer "F.Fab")
			(hide yes)
			(effects
				(font
					(size 1.016 1.016)
					(thickness 0.1524)
				)
			)
		)
		(property "Device Type" "R402H16"
			(at 0.064008 -5.517896 270)
			(unlocked yes)
			(layer "F.Fab")
			(hide yes)
			(effects
				(font
					(size 1.016 1.016)
					(thickness 0.1524)
				)
			)
		)
		(duplicate_pad_numbers_are_jumpers no)
		(fp_line
			(start -0.508 -0.9398)
			(end -0.508 0.9398)
			(stroke
				(width 0.1524)
				(type default)
			)
			(layer "F.SilkS")
		)
		(fp_line
			(start 0.508 -0.9398)
			(end -0.508 -0.9398)
			(stroke
				(width 0.1524)
				(type default)
			)
			(layer "F.SilkS")
		)
		(fp_rect
			(start -0.508 0.9398)
			(end 0.508 -0.9398)
			(stroke
				(width 0)
				(type default)
			)
			(fill no)
			(layer "F.CrtYd")
		)
		(fp_rect
			(start -0.508 0.9398)
			(end 0.508 -0.9398)
			(stroke
				(width 0)
				(type default)
			)
			(fill no)
			(layer "F.Fab")
		)
		(pad "1" smd custom
			(at 0 -0.4445 270)
			(size 0.1397 0.1397)
			(layers "F.Cu" "F.Mask" "F.Paste")
			(net "P3V3")
			(options
				(clearance outline)
				(anchor circle)
			)
			(primitives
				(gr_poly
					(pts
						(arc
							(start -0.1778 -0.2794)
							(mid -0.249642 -0.249642)
							(end -0.2794 -0.1778)
						)
						(arc
							(start -0.2794 0.1778)
							(mid -0.249642 0.249642)
							(end -0.1778 0.2794)
						)
						(arc
							(start 0.1778 0.2794)
							(mid 0.249642 0.249642)
							(end 0.2794 0.1778)
						)
						(arc
							(start 0.2794 -0.1778)
							(mid 0.249642 -0.249642)
							(end 0.1778 -0.2794)
						)
					)
					(width 0)
					(fill yes)
				)
			)
		)
		(pad "2" smd custom
			(at 0 0.4445 270)
			(size 0.1397 0.1397)
			(layers "F.Cu" "F.Mask" "F.Paste")
			(net "DRV_ATTN_12")
			(options
				(clearance outline)
				(anchor circle)
			)
			(primitives
				(gr_poly
					(pts
						(arc
							(start -0.1778 -0.2794)
							(mid -0.249642 -0.249642)
							(end -0.2794 -0.1778)
						)
						(arc
							(start -0.2794 0.1778)
							(mid -0.249642 0.249642)
							(end -0.1778 0.2794)
						)
						(arc
							(start 0.1778 0.2794)
							(mid 0.249642 0.249642)
							(end 0.2794 0.1778)
						)
						(arc
							(start 0.2794 -0.1778)
							(mid 0.249642 -0.249642)
							(end 0.1778 -0.2794)
						)
					)
					(width 0)
					(fill yes)
				)
			)
		)
	)
	(footprint ""
		(layer "F.Cu")
		(at 70.739 -145.542 90)
		(property "Reference" "SR966"
			(at 0 0 90)
			(layer "F.SilkS")
			(hide yes)
			(effects
				(font
					(size 1.27 1.27)
				)
			)
		)
		(property "Value" "2KR2F-3-GP"
			(at 0.064008 -3.993896 90)
			(unlocked yes)
			(layer "F.Fab")
			(hide yes)
			(effects
				(font
					(size 1.016 1.016)
					(thickness 0.1524)
				)
			)
		)
		(property "Device Type" "R402H16"
			(at 0.064008 -5.517896 90)
			(unlocked yes)
			(layer "F.Fab")
			(hide yes)
			(effects
				(font
					(size 1.016 1.016)
					(thickness 0.1524)
				)
			)
		)
		(duplicate_pad_numbers_are_jumpers no)
		(fp_line
			(start 0.508 -0.9398)
			(end -0.508 -0.9398)
			(stroke
				(width 0.1524)
				(type default)
			)
			(layer "F.SilkS")
		)
		(fp_line
			(start -0.508 -0.9398)
			(end -0.508 0.9398)
			(stroke
				(width 0.1524)
				(type default)
			)
			(layer "F.SilkS")
		)
		(fp_rect
			(start -0.508 0.9398)
			(end 0.508 -0.9398)
			(stroke
				(width 0)
				(type default)
			)
			(fill no)
			(layer "F.CrtYd")
		)
		(fp_rect
			(start -0.508 0.9398)
			(end 0.508 -0.9398)
			(stroke
				(width 0)
				(type default)
			)
			(fill no)
			(layer "F.Fab")
		)
		(pad "1" smd custom
			(at 0 -0.4445 90)
			(size 0.1397 0.1397)
			(layers "F.Cu" "F.Mask" "F.Paste")
			(net "P3V3")
			(options
				(clearance outline)
				(anchor circle)
			)
			(primitives
				(gr_poly
					(pts
						(arc
							(start -0.1778 -0.2794)
							(mid -0.249642 -0.249642)
							(end -0.2794 -0.1778)
						)
						(arc
							(start -0.2794 0.1778)
							(mid -0.249642 0.249642)
							(end -0.1778 0.2794)
						)
						(arc
							(start 0.1778 0.2794)
							(mid 0.249642 0.249642)
							(end 0.2794 0.1778)
						)
						(arc
							(start 0.2794 -0.1778)
							(mid 0.249642 -0.249642)
							(end 0.1778 -0.2794)
						)
					)
					(width 0)
					(fill yes)
				)
			)
		)
		(pad "2" smd custom
			(at 0 0.4445 90)
			(size 0.1397 0.1397)
			(layers "F.Cu" "F.Mask" "F.Paste")
			(net "SDA_DR9")
			(options
				(clearance outline)
				(anchor circle)
			)
			(primitives
				(gr_poly
					(pts
						(arc
							(start -0.1778 -0.2794)
							(mid -0.249642 -0.249642)
							(end -0.2794 -0.1778)
						)
						(arc
							(start -0.2794 0.1778)
							(mid -0.249642 0.249642)
							(end -0.1778 0.2794)
						)
						(arc
							(start 0.1778 0.2794)
							(mid 0.249642 0.249642)
							(end 0.2794 0.1778)
						)
						(arc
							(start 0.2794 -0.1778)
							(mid 0.249642 -0.249642)
							(end 0.1778 -0.2794)
						)
					)
					(width 0)
					(fill yes)
				)
			)
		)
	)
	(footprint ""
		(layer "F.Cu")
		(at 23.998174 -371.083332 -90)
		(property "Reference" "U208"
			(at 0 0 270)
			(layer "F.SilkS")
			(hide yes)
			(effects
				(font
					(size 1.27 1.27)
				)
			)
		)
		(property "Value" "SN74LVC1G08DCKR-GP"
			(at -2.3368 -8.6868 270)
			(unlocked yes)
			(layer "F.Fab")
			(hide yes)
			(effects
				(font
					(size 1.016 1.016)
					(thickness 0.1524)
				)
			)
		)
		(property "Device Type" "SC70-5H44"
			(at -2.3114 -10.414 270)
			(unlocked yes)
			(layer "F.Fab")
			(hide yes)
			(effects
				(font
					(size 1.016 1.016)
					(thickness 0.1524)
				)
			)
		)
		(duplicate_pad_numbers_are_jumpers no)
		(fp_line
			(start -1.27 1.7018)
			(end -1.27 -1.7018)
			(stroke
				(width 0.1524)
				(type default)
			)
			(layer "F.SilkS")
		)
		(fp_line
			(start 1.27 1.7018)
			(end -1.27 1.7018)
			(stroke
				(width 0.1524)
				(type default)
			)
			(layer "F.SilkS")
		)
		(fp_line
			(start -1.27 -1.7018)
			(end 1.27 -1.7018)
			(stroke
				(width 0.1524)
				(type default)
			)
			(layer "F.SilkS")
		)
		(fp_line
			(start 1.27 -1.7018)
			(end 1.27 1.7018)
			(stroke
				(width 0.1524)
				(type default)
			)
			(layer "F.SilkS")
		)
		(fp_line
			(start 0.6604 -1.8034)
			(end 1.3843 -1.8034)
			(stroke
				(width 0.3302)
				(type default)
			)
			(layer "F.SilkS")
		)
		(fp_line
			(start 1.3843 -1.8034)
			(end 1.3843 -1.1176)
			(stroke
				(width 0.3302)
				(type default)
			)
			(layer "F.SilkS")
		)
		(fp_rect
			(start -1.524 1.9558)
			(end 1.524 -1.9558)
			(stroke
				(width 0)
				(type default)
			)
			(fill no)
			(layer "F.CrtYd")
		)
		(fp_poly
			(pts
				(xy -1.524 -1.9558) (xy 1.524 -1.9558) (xy 1.524 1.9558) (xy -1.524 1.9558)
			)
			(stroke
				(width 0)
				(type default)
			)
			(fill no)
			(layer "F.Fab")
		)
		(pad "1" smd rect
			(at 0.65024 -0.8255 270)
			(size 0.4064 1.2192)
			(layers "F.Cu" "F.Mask" "F.Paste")
			(net "SSD11_CLK0_OE_MOS_N")
		)
		(pad "2" smd rect
			(at 0 -0.8255 270)
			(size 0.4064 1.2192)
			(layers "F.Cu" "F.Mask" "F.Paste")
			(net "ATTN_LED_DR11_N")
		)
		(pad "3" smd rect
			(at -0.65024 -0.8255 270)
			(size 0.4064 1.2192)
			(layers "F.Cu" "F.Mask" "F.Paste")
			(net "GND")
		)
		(pad "4" smd rect
			(at -0.65024 0.8255 270)
			(size 0.4064 1.2192)
			(layers "F.Cu" "F.Mask" "F.Paste")
			(net "ATTN_LED_DR11_AND")
		)
		(pad "5" smd rect
			(at 0.65024 0.8255 270)
			(size 0.4064 1.2192)
			(layers "F.Cu" "F.Mask" "F.Paste")
			(net "P3V3")
		)
	)
	(footprint ""
		(layer "F.Cu")
		(at 222.123 -142.10411)
		(property "Reference" "Q45"
			(at 0 0 0)
			(layer "F.SilkS")
			(hide yes)
			(effects
				(font
					(size 1.27 1.27)
				)
			)
		)
		(property "Value" "2N7002A-7-GP"
			(at 0.127 -8.9662 0)
			(unlocked yes)
			(layer "F.Fab")
			(hide yes)
			(effects
				(font
					(size 1.016 1.016)
					(thickness 0.1524)
				)
			)
		)
		(property "Device Type" "SOT23DGS2D4H48"
			(at 0.127 -10.4902 0)
			(unlocked yes)
			(layer "F.Fab")
			(hide yes)
			(effects
				(font
					(size 1.016 1.016)
					(thickness 0.1524)
				)
			)
		)
		(duplicate_pad_numbers_are_jumpers no)
		(fp_line
			(start -1.651 -1.778)
			(end -1.651 1.778)
			(stroke
				(width 0.1524)
				(type default)
			)
			(layer "F.SilkS")
		)
		(fp_line
			(start -1.651 1.778)
			(end 1.651 1.778)
			(stroke
				(width 0.1524)
				(type default)
			)
			(layer "F.SilkS")
		)
		(fp_line
			(start 1.651 -1.778)
			(end -1.651 -1.778)
			(stroke
				(width 0.1524)
				(type default)
			)
			(layer "F.SilkS")
		)
		(fp_line
			(start 1.651 1.778)
			(end 1.651 -1.778)
			(stroke
				(width 0.1524)
				(type default)
			)
			(layer "F.SilkS")
		)
		(fp_poly
			(pts
				(xy -1.778 1.8796) (xy -1.778 -1.8796) (xy 1.778 -1.8796) (xy 1.778 1.8796)
			)
			(stroke
				(width 0)
				(type default)
			)
			(fill no)
			(layer "F.CrtYd")
		)
		(fp_poly
			(pts
				(xy -1.778 1.8796) (xy -1.778 -1.8796) (xy 1.778 -1.8796) (xy 1.778 1.8796)
			)
			(stroke
				(width 0)
				(type default)
			)
			(fill no)
			(layer "F.Fab")
		)
		(pad "D" smd custom
			(at 0 -0.9525)
			(size 0.1905 0.1905)
			(layers "F.Cu" "F.Mask" "F.Paste")
			(net "ATTN_LED_DR3_MOS_N")
			(options
				(clearance outline)
				(anchor circle)
			)
			(primitives
				(gr_poly
					(pts
						(arc
							(start -0.1778 0.5715)
							(mid -0.321484 0.511984)
							(end -0.381 0.3683)
						)
						(arc
							(start -0.381 -0.3683)
							(mid -0.321484 -0.511984)
							(end -0.1778 -0.5715)
						)
						(arc
							(start 0.1778 -0.5715)
							(mid 0.321484 -0.511984)
							(end 0.381 -0.3683)
						)
						(arc
							(start 0.381 0.3683)
							(mid 0.321484 0.511984)
							(end 0.1778 0.5715)
						)
					)
					(width 0)
					(fill yes)
				)
			)
		)
		(pad "G" smd custom
			(at -0.98425 0.9525)
			(size 0.1905 0.1905)
			(layers "F.Cu" "F.Mask" "F.Paste")
			(net "SSD3_CLK0_OE_MOS_N")
			(options
				(clearance outline)
				(anchor circle)
			)
			(primitives
				(gr_poly
					(pts
						(arc
							(start -0.1778 0.5715)
							(mid -0.321484 0.511984)
							(end -0.381 0.3683)
						)
						(arc
							(start -0.381 -0.3683)
							(mid -0.321484 -0.511984)
							(end -0.1778 -0.5715)
						)
						(arc
							(start 0.1778 -0.5715)
							(mid 0.321484 -0.511984)
							(end 0.381 -0.3683)
						)
						(arc
							(start 0.381 0.3683)
							(mid 0.321484 0.511984)
							(end 0.1778 0.5715)
						)
					)
					(width 0)
					(fill yes)
				)
			)
		)
		(pad "S" smd custom
			(at 0.98425 0.9525)
			(size 0.1905 0.1905)
			(layers "F.Cu" "F.Mask" "F.Paste")
			(net "ATTN_LED_DR3_R")
			(options
				(clearance outline)
				(anchor circle)
			)
			(primitives
				(gr_poly
					(pts
						(arc
							(start -0.1778 0.5715)
							(mid -0.321484 0.511984)
							(end -0.381 0.3683)
						)
						(arc
							(start -0.381 -0.3683)
							(mid -0.321484 -0.511984)
							(end -0.1778 -0.5715)
						)
						(arc
							(start 0.1778 -0.5715)
							(mid 0.321484 -0.511984)
							(end 0.381 -0.3683)
						)
						(arc
							(start 0.381 0.3683)
							(mid 0.321484 0.511984)
							(end 0.1778 0.5715)
						)
					)
					(width 0)
					(fill yes)
				)
			)
		)
	)
	(footprint ""
		(layer "F.Cu")
		(at 90.297 -110.236 180)
		(property "Reference" "R9062"
			(at 0 0 180)
			(layer "F.SilkS")
			(hide yes)
			(effects
				(font
					(size 1.27 1.27)
				)
			)
		)
		(property "Value" "27R2F-GP"
			(at 0.064008 -3.993896 180)
			(unlocked yes)
			(layer "F.Fab")
			(hide yes)
			(effects
				(font
					(size 1.016 1.016)
					(thickness 0.1524)
				)
			)
		)
		(property "Device Type" "R402H16"
			(at 0.064008 -5.517896 180)
			(unlocked yes)
			(layer "F.Fab")
			(hide yes)
			(effects
				(font
					(size 1.016 1.016)
					(thickness 0.1524)
				)
			)
		)
		(duplicate_pad_numbers_are_jumpers no)
		(fp_line
			(start 0.508 -0.9398)
			(end -0.508 -0.9398)
			(stroke
				(width 0.1524)
				(type default)
			)
			(layer "F.SilkS")
		)
		(fp_line
			(start -0.508 -0.9398)
			(end -0.508 0.9398)
			(stroke
				(width 0.1524)
				(type default)
			)
			(layer "F.SilkS")
		)
		(fp_rect
			(start -0.508 0.9398)
			(end 0.508 -0.9398)
			(stroke
				(width 0)
				(type default)
			)
			(fill no)
			(layer "F.CrtYd")
		)
		(fp_rect
			(start -0.508 0.9398)
			(end 0.508 -0.9398)
			(stroke
				(width 0)
				(type default)
			)
			(fill no)
			(layer "F.Fab")
		)
		(pad "1" smd custom
			(at 0 -0.4445 180)
			(size 0.1397 0.1397)
			(layers "F.Cu" "F.Mask" "F.Paste")
			(net "PE_CLK_100M_DR13_2_R_N")
			(options
				(clearance outline)
				(anchor circle)
			)
			(primitives
				(gr_poly
					(pts
						(arc
							(start -0.1778 -0.2794)
							(mid -0.249642 -0.249642)
							(end -0.2794 -0.1778)
						)
						(arc
							(start -0.2794 0.1778)
							(mid -0.249642 0.249642)
							(end -0.1778 0.2794)
						)
						(arc
							(start 0.1778 0.2794)
							(mid 0.249642 0.249642)
							(end 0.2794 0.1778)
						)
						(arc
							(start 0.2794 -0.1778)
							(mid 0.249642 -0.249642)
							(end 0.1778 -0.2794)
						)
					)
					(width 0)
					(fill yes)
				)
			)
		)
		(pad "2" smd custom
			(at 0 0.4445 180)
			(size 0.1397 0.1397)
			(layers "F.Cu" "F.Mask" "F.Paste")
			(net "PE_CLK100M_DR13_2_N")
			(options
				(clearance outline)
				(anchor circle)
			)
			(primitives
				(gr_poly
					(pts
						(arc
							(start -0.1778 -0.2794)
							(mid -0.249642 -0.249642)
							(end -0.2794 -0.1778)
						)
						(arc
							(start -0.2794 0.1778)
							(mid -0.249642 0.249642)
							(end -0.1778 0.2794)
						)
						(arc
							(start 0.1778 0.2794)
							(mid 0.249642 0.249642)
							(end 0.2794 0.1778)
						)
						(arc
							(start 0.2794 -0.1778)
							(mid 0.249642 -0.249642)
							(end 0.1778 -0.2794)
						)
					)
					(width 0)
					(fill yes)
				)
			)
		)
	)
)
